FILE_TYPE = MACRO_DRAWING;
SET COLOR_WIRE YELLOW;
SET COLOR_PROP ORANGE;
SET COLOR_DOT WHITE;
SET COLOR_ARC YELLOW;
SET COLOR_BODY GREEN;
SET COLOR_NOTE PURPLE;
SET PROP_DISPLAY VALUE;
SET PAGE_NUMBER P213;
FORCEADD QUANTA_TITLE_BLOCK_C..1
(0 0);
FORCEPROP 1 LAST CUSTOM_TXT_CDS <NAME_2>
J 0
(-3175 50);
FORCEPROP 1 LAST CUSTOM_TXT_CDS <NAME_1>
J 0
(-3175 175);
FORCEPROP 1 LAST CUSTOM_TXT_CDS <Q_NUMBER>
J 0
(-1403 103);
DISPLAY 1.212766 (-1403 103);
FORCEPROP 1 LAST CUSTOM_TXT_CDS <Q_PROJ>
J 0
(-2382 102);
DISPLAY 1.212766 (-2382 102);
FORCEPROP 1 LAST CUSTOM_TXT_CDS <Q_REV>
J 0
(-184 103);
DISPLAY 1.212766 (-184 103);
FORCEPROP 1 LAST CUSTOM_TXT_CDS <CON_LAST_MODIFIED>
J 0
(-1885 15);
DISPLAY 0.978723 (-1885 15);
FORCEPROP 1 LAST CUSTOM_TXT_CDS <CON_PAGE_NUM> OF <CON_TOTAL_PAGES>
J 0
(-446 18);
DISPLAY 0.978723 (-446 18);
FORCEPROP 1 LAST Q_TITLE DUMMY SUMBOL
J 0
(-9366 26);
DISPLAY 2.446809 (-9366 26);
PAINT GREEN (-9366 26);
FORCEPROP 1 LAST Q_DEPT BU9
J 1
(-3763 49);
DISPLAY 1.957447 (-3763 49);
PAINT GREEN (-3763 49);
FORCEPROP 1 LAST COMMENT_BODY TRUE
J 0
(12 -13);
DISPLAY 0.978723 (12 -13);
PAINT GREEN (12 -13);
DISPLAY INVISIBLE (12 -13);
FORCEPROP 2 LAST CDS_LIB pure_quanta
J 0
(0 0);
DISPLAY INVISIBLE (0 0);
FORCEPROP 1 LAST CDS_LMAN_SYM_OUTLINE -9475,6775,100,-125
J 0
(0 0);
DISPLAY 0.468085 (0 0);
PAINT GREEN (0 0);
DISPLAY INVISIBLE (0 0);
FORCEPROP 2 LAST PAGE_BORDER TRUE
J 0
(-7890 5250);
DISPLAY 0.638298 (-7890 5250);
PAINT PINK (-7890 5250);
DISPLAY INVISIBLE (-7890 5250);
FORCEPROP 2 LAST CDS_XR_PAGE_TITLE CR-214 : @T6G_MB_LIB.T6G(SCH_1):PAGE214
J 0
(-7890 5250);
DISPLAY 0.638298 (-7890 5250);
PAINT PINK (-7890 5250);
DISPLAY INVISIBLE (-7890 5250);
FORCEPROP 2 LAST CUSTOM_TXT_CDS <XR_PAGE_TITLE>
J 0
(-7890 5250);
DISPLAY 0.638298 (-7890 5250);
PAINT PINK (-7890 5250);
DISPLAY INVISIBLE (-7890 5250);
FORCEPROP 0 LAST CDS_CON_LAST_MODIFIED Wed Mar 09 21:49:17 2022
J 0
(-1885 15);
DISPLAY INVISIBLE (-1885 15);
QUIT
